Created on Valor NPI 9.6 Update 2 - Netlist Compare Summary.
DATE :  09 Jun 2017
TIME :  18:25:23


     MISMATCH SUMMARY REPORT
     -----------------------

Job  : 16317-1                 Job  : 16317-1
Step : q                       Step : q
Type : CAD                     Type : CURCAD

-----------------------------------------------

 Mismatch Type: shorted

   GND                   -   NET00000            
   AGND_CURRENT_DPB      -    "                  
   AGND_CURRENT_MON      -    "                  
   AGND_P5V_B_4          -    "                  
   AGND_P5V_B_2          -    "                  
   AGND_P5V_B_1          -    "                  
   AGND_P5V_B_3          -    "                  
   AGND_P3V3_STBY        -    "                  
   P3V3_STBY_B           -   NET00013            
   P3V3_STBY_CC          -    "                  
   P5V_B_4               -   NET00179            
   P5V_B_4_CC            -    "                  
   P5V_B_2               -   NET00188            
   P5V_B_2_CC            -    "                  
   P5V_B_3               -   NET00540            
   P5V_B_3_CC            -    "                  
   P5V_B_1               -   NET00554            
   P5V_B_1_CC            -    "                  

 Total : 6
-----------------------------------------------

 Mismatch Type: broken


 Total : 0
-----------------------------------------------

 Mismatch Type: missing


 Total : 0
-----------------------------------------------

 Mismatch Type: extra


 Total : 0
-----------------------------------------------
